(kicad_pcb
	(version 20260206)
	(generator "pcbnew")
	(generator_version "10.0")
	(general
		(thickness 1.6)
		(legacy_teardrops no)
	)
	(paper "A4")
	(title_block
		(title "01162023_DA0F0TEBIF0_F0T_Expander_BD_F_brd_V02_OCP.brd")
		(comment 1 "Grand Teton / footprints 5234-5238 of 9728")
	)
	(layers
		(0 "F.Cu" signal "TOP")
		(4 "In1.Cu" signal "GND")
		(6 "In2.Cu" signal "VCC")
		(8 "In3.Cu" signal "VCC1")
		(10 "In4.Cu" signal "GND1")
		(12 "In5.Cu" signal "IN1")
		(14 "In6.Cu" signal "GND2")
		(16 "In7.Cu" signal "IN2")
		(18 "In8.Cu" signal "GND3")
		(20 "In9.Cu" signal "IN3")
		(22 "In10.Cu" signal "GND4")
		(24 "In11.Cu" signal "IN4")
		(26 "In12.Cu" signal "GND5")
		(28 "In13.Cu" signal "IN5")
		(30 "In14.Cu" signal "GND6")
		(32 "In15.Cu" signal "IN6")
		(34 "In16.Cu" signal "GND7")
		(2 "B.Cu" signal "BOTTOM")
		(9 "F.Adhes" user "F.Adhesive")
		(11 "B.Adhes" user "B.Adhesive")
		(13 "F.Paste" user "Package Geometry/Pastemask Top")
		(15 "B.Paste" user "Package Geometry/Pastemask Bottom")
		(5 "F.SilkS" user "Ref Des/Silkscreen Top")
		(7 "B.SilkS" user "Ref Des/Silkscreen Bottom")
		(1 "F.Mask" user "Board Geometry/Soldermask Top")
		(3 "B.Mask" user "Board Geometry/Soldermask Bottom")
		(17 "Dwgs.User" user "User.Drawings")
		(19 "Cmts.User" user "User.Comments")
		(21 "Eco1.User" user "User.Eco1")
		(23 "Eco2.User" user "User.Eco2")
		(25 "Edge.Cuts" user "Board Geometry/Outline")
		(27 "Margin" user)
		(31 "F.CrtYd" user "Package Geometry/Place Bound Top")
		(29 "B.CrtYd" user "Package Geometry/Place Bound Bottom")
		(35 "F.Fab" user "Ref Des/Assembly Top")
		(33 "B.Fab" user "Ref Des/Assembly Bottom")
	)
	(footprint ""
		(layer "F.Cu")
		(at 409.015438 -87.440008 180)
		(property "Reference" "R6269"
			(at 0 0 180)
			(layer "F.SilkS")
			(hide yes)
			(effects
				(font
					(size 1.27 1.27)
				)
			)
		)
		(property "Value" ""
			(at 0 0 180)
			(layer "F.Fab")
			(effects
				(font
					(size 1.27 1.27)
				)
			)
		)
		(duplicate_pad_numbers_are_jumpers no)
		(fp_line
			(start 0.7874 0.4064)
			(end -0.7874 0.4064)
			(stroke
				(width 0.1524)
				(type default)
			)
			(layer "F.SilkS")
		)
		(fp_line
			(start 0.7874 -0.4064)
			(end 0.7874 0.4064)
			(stroke
				(width 0.1524)
				(type default)
			)
			(layer "F.SilkS")
		)
		(fp_line
			(start -0.7874 0.4064)
			(end -0.7874 -0.4064)
			(stroke
				(width 0.1524)
				(type default)
			)
			(layer "F.SilkS")
		)
		(fp_line
			(start -0.7874 -0.4064)
			(end 0.7874 -0.4064)
			(stroke
				(width 0.1524)
				(type default)
			)
			(layer "F.SilkS")
		)
		(fp_line
			(start 0.67945 0.3048)
			(end 0.120396 0.3048)
			(stroke
				(width 0.1)
				(type default)
			)
			(layer "F.Fab")
		)
		(fp_line
			(start 0.67945 -0.3048)
			(end 0.67945 0.3048)
			(stroke
				(width 0.1)
				(type default)
			)
			(layer "F.Fab")
		)
		(fp_line
			(start 0.12065 -0.2794)
			(end 0.12065 -0.3048)
			(stroke
				(width 0.1)
				(type default)
			)
			(layer "F.Fab")
		)
		(fp_line
			(start 0.12065 -0.3048)
			(end 0.67945 -0.3048)
			(stroke
				(width 0.1)
				(type default)
			)
			(layer "F.Fab")
		)
		(fp_line
			(start 0.120396 0.3048)
			(end 0.120396 0.2794)
			(stroke
				(width 0.1)
				(type default)
			)
			(layer "F.Fab")
		)
		(fp_line
			(start 0.120396 0.2794)
			(end -0.12065 0.2794)
			(stroke
				(width 0.1)
				(type default)
			)
			(layer "F.Fab")
		)
		(fp_line
			(start -0.12065 0.3048)
			(end -0.67945 0.3048)
			(stroke
				(width 0.1)
				(type default)
			)
			(layer "F.Fab")
		)
		(fp_line
			(start -0.12065 0.2794)
			(end -0.12065 0.3048)
			(stroke
				(width 0.1)
				(type default)
			)
			(layer "F.Fab")
		)
		(fp_line
			(start -0.12065 -0.2794)
			(end 0.12065 -0.2794)
			(stroke
				(width 0.1)
				(type default)
			)
			(layer "F.Fab")
		)
		(fp_line
			(start -0.12065 -0.305054)
			(end -0.12065 -0.2794)
			(stroke
				(width 0.1)
				(type default)
			)
			(layer "F.Fab")
		)
		(fp_line
			(start -0.67945 0.3048)
			(end -0.67945 -0.305054)
			(stroke
				(width 0.1)
				(type default)
			)
			(layer "F.Fab")
		)
		(fp_line
			(start -0.67945 -0.305054)
			(end -0.12065 -0.305054)
			(stroke
				(width 0.1)
				(type default)
			)
			(layer "F.Fab")
		)
		(pad "1" smd circle
			(at -0.40005 0 180)
			(size 0 0)
			(layers "F.Cu" "F.Mask" "F.Paste")
			(net "SMB_CLK_ISO_R_SDA")
		)
		(pad "2" smd circle
			(at 0.40005 0 180)
			(size 0 0)
			(layers "F.Cu" "F.Mask" "F.Paste")
			(net "SMB_CLK_ISO_SDA")
		)
	)
	(footprint ""
		(layer "F.Cu")
		(at 107.612942 -111.785654 180)
		(property "Reference" "PU72"
			(at 3.674872 -1.397254 90)
			(unlocked yes)
			(layer "F.SilkS")
			(effects
				(font
					(size 0.7874 0.5842)
					(thickness 0.1524)
				)
				(justify left)
			)
		)
		(property "Value" ""
			(at 0 0 180)
			(layer "F.Fab")
			(effects
				(font
					(size 1.27 1.27)
				)
			)
		)
		(duplicate_pad_numbers_are_jumpers no)
		(fp_line
			(start 1.549908 2.549906)
			(end 1.549908 2.253996)
			(stroke
				(width 0.1524)
				(type default)
			)
			(layer "F.SilkS")
		)
		(fp_line
			(start 1.549908 -2.253996)
			(end 1.549908 -2.549906)
			(stroke
				(width 0.1524)
				(type default)
			)
			(layer "F.SilkS")
		)
		(fp_line
			(start 1.549908 -2.549906)
			(end 0.752094 -2.549906)
			(stroke
				(width 0.1524)
				(type default)
			)
			(layer "F.SilkS")
		)
		(fp_line
			(start 0.753872 2.549906)
			(end 1.549908 2.549906)
			(stroke
				(width 0.1524)
				(type default)
			)
			(layer "F.SilkS")
		)
		(fp_line
			(start 0.2413 -2.549906)
			(end -0.2413 -2.549906)
			(stroke
				(width 0.1524)
				(type default)
			)
			(layer "F.SilkS")
		)
		(fp_line
			(start -0.245872 2.549906)
			(end 0.245872 2.549906)
			(stroke
				(width 0.1524)
				(type default)
			)
			(layer "F.SilkS")
		)
		(fp_line
			(start -0.752094 -2.549906)
			(end -1.549908 -2.549906)
			(stroke
				(width 0.1524)
				(type default)
			)
			(layer "F.SilkS")
		)
		(fp_line
			(start -1.549908 2.549906)
			(end -0.753872 2.549906)
			(stroke
				(width 0.1524)
				(type default)
			)
			(layer "F.SilkS")
		)
		(fp_line
			(start -1.549908 2.253996)
			(end -1.549908 2.549906)
			(stroke
				(width 0.1524)
				(type default)
			)
			(layer "F.SilkS")
		)
		(fp_line
			(start -1.549908 -2.549906)
			(end -1.549908 -2.251964)
			(stroke
				(width 0.1524)
				(type default)
			)
			(layer "F.SilkS")
		)
		(fp_poly
			(pts
				(xy -1.891538 -1.999996) (xy -2.7432 -1.574292) (xy -2.7432 -2.4257)
			)
			(stroke
				(width 0)
				(type default)
			)
			(fill yes)
			(layer "F.SilkS")
		)
		(fp_line
			(start 1.549908 2.549906)
			(end 1.549908 -2.549906)
			(stroke
				(width 0.1)
				(type default)
			)
			(layer "F.Fab")
		)
		(fp_line
			(start 1.549908 -2.549906)
			(end -1.549908 -2.549906)
			(stroke
				(width 0.1)
				(type default)
			)
			(layer "F.Fab")
		)
		(fp_line
			(start -1.549908 2.549906)
			(end 1.549908 2.549906)
			(stroke
				(width 0.1)
				(type default)
			)
			(layer "F.Fab")
		)
		(fp_line
			(start -1.549908 -2.549906)
			(end -1.549908 2.549906)
			(stroke
				(width 0.1)
				(type default)
			)
			(layer "F.Fab")
		)
		(fp_poly
			(pts
				(xy -1.891538 -1.999996) (xy -2.7432 -1.574292) (xy -2.7432 -2.4257)
			)
			(stroke
				(width 0)
				(type default)
			)
			(fill yes)
			(layer "F.Fab")
		)
		(fp_text user "12"
			(at 2.482342 1.081786 90)
			(unlocked yes)
			(layer "F.SilkS")
			(effects
				(font
					(size 0.635 0.4064)
					(thickness 0.1524)
				)
			)
		)
		(fp_text user "20"
			(at 2.055368 -2.7686 90)
			(unlocked yes)
			(layer "F.SilkS")
			(effects
				(font
					(size 0.635 0.4064)
					(thickness 0.1524)
				)
			)
		)
		(fp_text user "11"
			(at 1.245362 3.077464 180)
			(unlocked yes)
			(layer "F.SilkS")
			(effects
				(font
					(size 0.635 0.4064)
					(thickness 0.1524)
				)
			)
		)
		(fp_text user "21_22"
			(at -1.138682 -3.574542 180)
			(unlocked yes)
			(layer "F.SilkS")
			(effects
				(font
					(size 0.635 0.4064)
					(thickness 0.1524)
				)
			)
		)
		(fp_text user "10"
			(at -1.4224 3.253232 180)
			(unlocked yes)
			(layer "F.SilkS")
			(effects
				(font
					(size 0.635 0.4064)
					(thickness 0.1524)
				)
			)
		)
		(fp_text user "9"
			(at -2.338832 2.5908 90)
			(unlocked yes)
			(layer "F.SilkS")
			(effects
				(font
					(size 0.635 0.4064)
					(thickness 0.1524)
				)
			)
		)
		(fp_text user "12"
			(at 2.207768 2.7178 90)
			(unlocked yes)
			(layer "F.Fab")
			(effects
				(font
					(size 0.635 0.4064)
					(thickness 0.1524)
				)
			)
		)
		(fp_text user "20"
			(at 2.055368 -2.7686 90)
			(unlocked yes)
			(layer "F.Fab")
			(effects
				(font
					(size 0.635 0.4064)
					(thickness 0.1524)
				)
			)
		)
		(fp_text user "11"
			(at 1.1938 3.329432 180)
			(unlocked yes)
			(layer "F.Fab")
			(effects
				(font
					(size 0.635 0.4064)
					(thickness 0.1524)
				)
			)
		)
		(fp_text user "21_22"
			(at -0.0762 -3.401568 180)
			(unlocked yes)
			(layer "F.Fab")
			(effects
				(font
					(size 0.635 0.4064)
					(thickness 0.1524)
				)
			)
		)
		(fp_text user "10"
			(at -1.4224 3.253232 180)
			(unlocked yes)
			(layer "F.Fab")
			(effects
				(font
					(size 0.635 0.4064)
					(thickness 0.1524)
				)
			)
		)
		(fp_text user "9"
			(at -2.338832 2.5908 90)
			(unlocked yes)
			(layer "F.Fab")
			(effects
				(font
					(size 0.635 0.4064)
					(thickness 0.1524)
				)
			)
		)
		(pad "1" smd circle
			(at -1.374902 -1.999996 90)
			(size 0 0)
			(layers "F.Cu" "F.Mask" "F.Paste")
			(net "P12V_NIC1_CO_EN")
		)
		(pad "2" smd rect
			(at -1.400048 -1.500124 90)
			(size 0.254 0.8128)
			(layers "F.Cu" "F.Mask" "F.Paste")
			(net "GND")
		)
		(pad "3" smd rect
			(at -1.400048 -0.999998 90)
			(size 0.254 0.8128)
			(layers "F.Cu" "F.Mask" "F.Paste")
			(net "GND")
		)
		(pad "4" smd rect
			(at -1.400048 -0.499872 90)
			(size 0.254 0.8128)
			(layers "F.Cu" "F.Mask" "F.Paste")
			(net "P12V_NIC1_CO_TIMER")
		)
		(pad "5" smd rect
			(at -1.400048 0 90)
			(size 0.254 0.8128)
			(layers "F.Cu" "F.Mask" "F.Paste")
			(net "P12V_NIC1_CO_ISET")
		)
		(pad "6" smd rect
			(at -1.400048 0.499872 90)
			(size 0.254 0.8128)
			(layers "F.Cu" "F.Mask" "F.Paste")
			(net "P12V_NIC1_CO_SS")
		)
		(pad "7" smd rect
			(at -1.400048 0.999998 90)
			(size 0.254 0.8128)
			(layers "F.Cu" "F.Mask" "F.Paste")
			(net "GND")
		)
		(pad "8" smd rect
			(at -1.400048 1.500124 90)
			(size 0.254 0.8128)
			(layers "F.Cu" "F.Mask" "F.Paste")
			(net "P12V_NIC1_CO_IMON_VR")
		)
		(pad "9" smd rect
			(at -1.400048 1.999996 90)
			(size 0.254 0.8128)
			(layers "F.Cu" "F.Mask" "F.Paste")
			(net "P12V_NIC1_CO_FLTB")
		)
		(pad "10" smd rect
			(at -0.499872 2.400046 180)
			(size 0.254 0.8128)
			(layers "F.Cu" "F.Mask" "F.Paste")
			(net "PWRGD_P12V_NIC1_CO")
		)
		(pad "11" smd rect
			(at 0.499872 2.400046 180)
			(size 0.254 0.8128)
			(layers "F.Cu" "F.Mask" "F.Paste")
			(net "P12V_NIC1_CO_OV_FB")
		)
		(pad "12" smd rect
			(at 1.400048 1.999996 90)
			(size 0.254 0.8128)
			(layers "F.Cu" "F.Mask" "F.Paste")
			(net "P12V_NIC1_CO_AVIN_PD")
		)
		(pad "13" smd rect
			(at 1.400048 1.500124 90)
			(size 0.254 0.8128)
			(layers "F.Cu" "F.Mask" "F.Paste")
			(net "P12V_NIC1_R")
		)
		(pad "14" smd rect
			(at 1.400048 0.999998 90)
			(size 0.254 0.8128)
			(layers "F.Cu" "F.Mask" "F.Paste")
			(net "P12V_NIC1_R")
		)
		(pad "15" smd rect
			(at 1.400048 0.499872 90)
			(size 0.254 0.8128)
			(layers "F.Cu" "F.Mask" "F.Paste")
			(net "P12V_NIC1_R")
		)
		(pad "16" smd rect
			(at 1.400048 0 90)
			(size 0.254 0.8128)
			(layers "F.Cu" "F.Mask" "F.Paste")
			(net "P12V_NIC1_R")
		)
		(pad "17" smd rect
			(at 1.400048 -0.499872 90)
			(size 0.254 0.8128)
			(layers "F.Cu" "F.Mask" "F.Paste")
			(net "P12V_NIC1_R")
		)
		(pad "18" smd rect
			(at 1.400048 -0.999998 90)
			(size 0.254 0.8128)
			(layers "F.Cu" "F.Mask" "F.Paste")
			(net "P12V_NIC1_R")
		)
		(pad "19" smd rect
			(at 1.400048 -1.500124 90)
			(size 0.254 0.8128)
			(layers "F.Cu" "F.Mask" "F.Paste")
			(net "P12V_NIC1_R")
		)
		(pad "20" smd rect
			(at 1.400048 -1.999996 90)
			(size 0.254 0.8128)
			(layers "F.Cu" "F.Mask" "F.Paste")
			(net "P12V_NIC1_R")
		)
		(pad "21_22" smd circle
			(at 0.499872 -2.337562 90)
			(size 0 0)
			(layers "F.Cu" "F.Mask" "F.Paste")
			(net "P12V_AUX")
		)
		(pad "23" smd rect
			(at 0 -1.100074 90)
			(size 0.254 1.27)
			(layers "F.Cu" "F.Mask" "F.Paste")
			(net "P12V_AUX")
		)
		(pad "24" smd rect
			(at 0 -0.199898 90)
			(size 0.254 1.27)
			(layers "F.Cu" "F.Mask" "F.Paste")
			(net "P12V_AUX")
		)
		(pad "25" smd rect
			(at 0 0.700024 90)
			(size 0.254 1.27)
			(layers "F.Cu" "F.Mask" "F.Paste")
			(net "P12V_AUX")
		)
		(pad "26" smd rect
			(at 0 1.599946 90)
			(size 0.254 1.27)
			(layers "F.Cu" "F.Mask" "F.Paste")
			(net "P12V_AUX")
		)
	)
	(footprint ""
		(layer "F.Cu")
		(at 404.28164 -157.8356)
		(property "Reference" "R354"
			(at 0 0 0)
			(layer "F.SilkS")
			(hide yes)
			(effects
				(font
					(size 1.27 1.27)
				)
			)
		)
		(property "Value" ""
			(at 0 0 0)
			(layer "F.Fab")
			(effects
				(font
					(size 1.27 1.27)
				)
			)
		)
		(duplicate_pad_numbers_are_jumpers no)
		(fp_line
			(start -0.7874 -0.4064)
			(end 0.7874 -0.4064)
			(stroke
				(width 0.1524)
				(type default)
			)
			(layer "F.SilkS")
		)
		(fp_line
			(start -0.7874 0.4064)
			(end -0.7874 -0.4064)
			(stroke
				(width 0.1524)
				(type default)
			)
			(layer "F.SilkS")
		)
		(fp_line
			(start 0.7874 -0.4064)
			(end 0.7874 0.4064)
			(stroke
				(width 0.1524)
				(type default)
			)
			(layer "F.SilkS")
		)
		(fp_line
			(start 0.7874 0.4064)
			(end -0.7874 0.4064)
			(stroke
				(width 0.1524)
				(type default)
			)
			(layer "F.SilkS")
		)
		(fp_line
			(start -0.67945 -0.305054)
			(end -0.12065 -0.305054)
			(stroke
				(width 0.1)
				(type default)
			)
			(layer "F.Fab")
		)
		(fp_line
			(start -0.67945 0.3048)
			(end -0.67945 -0.305054)
			(stroke
				(width 0.1)
				(type default)
			)
			(layer "F.Fab")
		)
		(fp_line
			(start -0.12065 -0.305054)
			(end -0.12065 -0.2794)
			(stroke
				(width 0.1)
				(type default)
			)
			(layer "F.Fab")
		)
		(fp_line
			(start -0.12065 -0.2794)
			(end 0.12065 -0.2794)
			(stroke
				(width 0.1)
				(type default)
			)
			(layer "F.Fab")
		)
		(fp_line
			(start -0.12065 0.2794)
			(end -0.12065 0.3048)
			(stroke
				(width 0.1)
				(type default)
			)
			(layer "F.Fab")
		)
		(fp_line
			(start -0.12065 0.3048)
			(end -0.67945 0.3048)
			(stroke
				(width 0.1)
				(type default)
			)
			(layer "F.Fab")
		)
		(fp_line
			(start 0.120396 0.2794)
			(end -0.12065 0.2794)
			(stroke
				(width 0.1)
				(type default)
			)
			(layer "F.Fab")
		)
		(fp_line
			(start 0.120396 0.3048)
			(end 0.120396 0.2794)
			(stroke
				(width 0.1)
				(type default)
			)
			(layer "F.Fab")
		)
		(fp_line
			(start 0.12065 -0.3048)
			(end 0.67945 -0.3048)
			(stroke
				(width 0.1)
				(type default)
			)
			(layer "F.Fab")
		)
		(fp_line
			(start 0.12065 -0.2794)
			(end 0.12065 -0.3048)
			(stroke
				(width 0.1)
				(type default)
			)
			(layer "F.Fab")
		)
		(fp_line
			(start 0.67945 -0.3048)
			(end 0.67945 0.3048)
			(stroke
				(width 0.1)
				(type default)
			)
			(layer "F.Fab")
		)
		(fp_line
			(start 0.67945 0.3048)
			(end 0.120396 0.3048)
			(stroke
				(width 0.1)
				(type default)
			)
			(layer "F.Fab")
		)
		(pad "1" smd circle
			(at -0.40005 0)
			(size 0 0)
			(layers "F.Cu" "F.Mask" "F.Paste")
			(net "RST_NIC6_PERST3_R_N")
		)
		(pad "2" smd circle
			(at 0.40005 0)
			(size 0 0)
			(layers "F.Cu" "F.Mask" "F.Paste")
			(net "RST_HP_NIC6_BUF_N")
		)
	)
	(footprint ""
		(layer "F.Cu")
		(at 478.056194 -553.484796 180)
		(property "Reference" "JPEX0_FW1"
			(at -4.0259 -1.402334 0)
			(unlocked yes)
			(layer "B.SilkS")
			(effects
				(font
					(size 0.7874 0.5842)
					(thickness 0.1524)
				)
				(justify mirror)
			)
		)
		(property "Value" ""
			(at 0 0 180)
			(layer "F.Fab")
			(effects
				(font
					(size 1.27 1.27)
				)
			)
		)
		(duplicate_pad_numbers_are_jumpers no)
		(pad "1" thru_hole circle
			(at 0 0 180)
			(size 0.4572 0.4572)
			(drill 0.2032)
			(layers "*.Cu" "*.Mask")
			(remove_unused_layers no)
			(net "Net_9090")
			(clearance 0.127)
			(thermal_gap 0.127)
			(padstack
				(mode front_inner_back)
				(layer "Inner"
					(shape circle)
					(size 0.4572 0.4572)
					(clearance 0.127)
				)
				(layer "B.Cu"
					(shape circle)
					(size 0.508 0.508)
					(clearance 0.1016)
				)
			)
		)
	)
	(footprint ""
		(layer "F.Cu")
		(at 231.30383 -308.568852)
		(property "Reference" "PJ11"
			(at 0 0 0)
			(layer "F.SilkS")
			(hide yes)
			(effects
				(font
					(size 1.27 1.27)
				)
			)
		)
		(property "Value" ""
			(at 0 0 0)
			(layer "F.Fab")
			(effects
				(font
					(size 1.27 1.27)
				)
			)
		)
		(duplicate_pad_numbers_are_jumpers no)
		(pad "1" smd circle
			(at -0.40005 0 90)
			(size 0 0)
			(layers "F.Cu" "F.Mask" "F.Paste")
			(net "SH_P1V25_PEX1_FB_P")
		)
		(pad "2" smd rect
			(at 0.40005 0 180)
			(size 0.4572 0.508)
			(layers "F.Cu" "F.Mask" "F.Paste")
			(net "P1V25_PEX1")
		)
		(zone
			(layer "F.Cu")
			(hatch none 0.5)
			(connect_pads
				(clearance 0)
			)
			(min_thickness 0.25)
			(keepout
				(tracks allowed)
				(vias not_allowed)
				(pads allowed)
				(copperpour not_allowed)
				(footprints allowed)
			)
			(placement
				(enabled no)
				(sheetname "")
			)
			(fill
				(thermal_gap 0.5)
				(thermal_bridge_width 0.5)
				(island_removal_mode 0)
			)
			(polygon
				(pts
					(xy 230.61803 -308.264052) (xy 231.98963 -308.264052) (xy 231.98963 -308.873652) (xy 230.61803 -308.873652)
				)
			)
		)
	)
)
